(kicad_pcb
	(version 20260206)
	(generator "pcbnew")
	(generator_version "10.0")
	(general
		(thickness 1.6)
		(legacy_teardrops no)
	)
	(paper "A4")
	(title_block
		(title "Bryce Canyon_R.DPB_16317-1_OCP.brd")
		(comment 1 "Bryce Canyon / footprints 1763-1768 of 2099")
	)
	(layers
		(0 "F.Cu" signal "TOP")
		(4 "In1.Cu" signal "L2GND")
		(6 "In2.Cu" signal "L3")
		(8 "In3.Cu" signal "L4VCC")
		(10 "In4.Cu" signal "L5VCC")
		(12 "In5.Cu" signal "L6")
		(14 "In6.Cu" signal "L7GND")
		(2 "B.Cu" signal "BOTTOM")
		(9 "F.Adhes" user "F.Adhesive")
		(11 "B.Adhes" user "B.Adhesive")
		(13 "F.Paste" user "Package Geometry/Pastemask Top")
		(15 "B.Paste" user "Package Geometry/Pastemask Bottom")
		(5 "F.SilkS" user "Ref Des/Silkscreen Top")
		(7 "B.SilkS" user "Ref Des/Silkscreen Bottom")
		(1 "F.Mask" user "Board Geometry/Soldermask Top")
		(3 "B.Mask" user "Board Geometry/Soldermask Bottom")
		(17 "Dwgs.User" user "User.Drawings")
		(19 "Cmts.User" user "User.Comments")
		(21 "Eco1.User" user "User.Eco1")
		(23 "Eco2.User" user "User.Eco2")
		(25 "Edge.Cuts" user "Board Geometry/Outline")
		(27 "Margin" user)
		(31 "F.CrtYd" user "Package Geometry/Place Bound Top")
		(29 "B.CrtYd" user "Package Geometry/Place Bound Bottom")
		(35 "F.Fab" user "Ref Des/Assembly Top")
		(33 "B.Fab" user "Ref Des/Assembly Bottom")
	)
	(footprint ""
		(layer "F.Cu")
		(at 283.365448 -356.304342 -90)
		(property "Reference" "C615"
			(at 0 0 270)
			(layer "F.SilkS")
			(hide yes)
			(effects
				(font
					(size 1.27 1.27)
				)
			)
		)
		(property "Value" "SCD1U16V2KX-3GP"
			(at 1.1811 -2.7051 270)
			(unlocked yes)
			(layer "F.Fab")
			(hide yes)
			(effects
				(font
					(size 1.016 1.016)
					(thickness 0.1524)
				)
			)
		)
		(property "Device Type" "C402H22"
			(at 1.1811 -4.2291 270)
			(unlocked yes)
			(layer "F.Fab")
			(hide yes)
			(effects
				(font
					(size 1.016 1.016)
					(thickness 0.1524)
				)
			)
		)
		(duplicate_pad_numbers_are_jumpers no)
		(fp_rect
			(start -0.4318 0.9525)
			(end 0.4318 -0.9525)
			(stroke
				(width 0)
				(type default)
			)
			(fill no)
			(layer "F.CrtYd")
		)
		(fp_rect
			(start -0.4318 0.9525)
			(end 0.4318 -0.9525)
			(stroke
				(width 0)
				(type default)
			)
			(fill no)
			(layer "F.Fab")
		)
		(pad "1" smd custom
			(at 0 -0.4445 270)
			(size 0.1524 0.1524)
			(layers "F.Cu" "F.Mask" "F.Paste")
			(net "P3V3_STBY_B")
			(options
				(clearance outline)
				(anchor circle)
			)
			(primitives
				(gr_poly
					(pts
						(arc
							(start 0.3048 -0.2032)
							(mid 0.275042 -0.275042)
							(end 0.2032 -0.3048)
						)
						(arc
							(start -0.2032 -0.3048)
							(mid -0.275042 -0.275042)
							(end -0.3048 -0.2032)
						)
						(arc
							(start -0.3048 0.2032)
							(mid -0.275042 0.275042)
							(end -0.2032 0.3048)
						)
						(arc
							(start 0.2032 0.3048)
							(mid 0.275042 0.275042)
							(end 0.3048 0.2032)
						)
					)
					(width 0)
					(fill yes)
				)
			)
		)
		(pad "2" smd custom
			(at 0 0.4445 270)
			(size 0.1524 0.1524)
			(layers "F.Cu" "F.Mask" "F.Paste")
			(net "GND")
			(options
				(clearance outline)
				(anchor circle)
			)
			(primitives
				(gr_poly
					(pts
						(arc
							(start 0.3048 -0.2032)
							(mid 0.275042 -0.275042)
							(end 0.2032 -0.3048)
						)
						(arc
							(start -0.2032 -0.3048)
							(mid -0.275042 -0.275042)
							(end -0.3048 -0.2032)
						)
						(arc
							(start -0.3048 0.2032)
							(mid -0.275042 0.275042)
							(end -0.2032 0.3048)
						)
						(arc
							(start 0.2032 0.3048)
							(mid 0.275042 0.275042)
							(end 0.3048 0.2032)
						)
					)
					(width 0)
					(fill yes)
				)
			)
		)
	)
	(footprint ""
		(layer "F.Cu")
		(at 340.5124 -360.8578)
		(property "Reference" "Q130"
			(at 0 0 0)
			(layer "F.SilkS")
			(hide yes)
			(effects
				(font
					(size 1.27 1.27)
				)
			)
		)
		(property "Value" "AO4407AL-GP"
			(at -3.707384 -1.5367 0)
			(unlocked yes)
			(layer "F.Fab")
			(hide yes)
			(effects
				(font
					(size 1.016 1.016)
					(thickness 0.1524)
				)
			)
		)
		(property "Device Type" "SOIC8H69"
			(at -3.707384 -3.0607 0)
			(unlocked yes)
			(layer "F.Fab")
			(hide yes)
			(effects
				(font
					(size 1.016 1.016)
					(thickness 0.1524)
				)
			)
		)
		(duplicate_pad_numbers_are_jumpers no)
		(fp_line
			(start -2.7432 -1.4224)
			(end -2.7432 1.4224)
			(stroke
				(width 0.1524)
				(type default)
			)
			(layer "F.SilkS")
		)
		(fp_line
			(start -2.7432 1.4224)
			(end -2.6416 1.4224)
			(stroke
				(width 0.1524)
				(type default)
			)
			(layer "F.SilkS")
		)
		(fp_line
			(start -2.7432 1.4224)
			(end 2.1336 1.4224)
			(stroke
				(width 0.1524)
				(type default)
			)
			(layer "F.SilkS")
		)
		(fp_line
			(start -2.7178 -0.508)
			(end -2.1844 -0.0508)
			(stroke
				(width 0.1524)
				(type default)
			)
			(layer "F.SilkS")
		)
		(fp_line
			(start -2.6289 3.4417)
			(end -2.6289 1.4732)
			(stroke
				(width 0.381)
				(type default)
			)
			(layer "F.SilkS")
		)
		(fp_line
			(start -2.1844 -0.0508)
			(end -2.7178 0.508)
			(stroke
				(width 0.1524)
				(type default)
			)
			(layer "F.SilkS")
		)
		(fp_line
			(start 2.1336 -1.4224)
			(end -2.7432 -1.4224)
			(stroke
				(width 0.1524)
				(type default)
			)
			(layer "F.SilkS")
		)
		(fp_line
			(start 2.1336 1.4224)
			(end 2.1336 -1.4224)
			(stroke
				(width 0.1524)
				(type default)
			)
			(layer "F.SilkS")
		)
		(fp_poly
			(pts
				(xy -2.2098 -1.4224) (xy -2.2098 1.4224) (xy 2.2098 1.4224) (xy 2.2098 -1.4224)
			)
			(stroke
				(width 0)
				(type default)
			)
			(fill yes)
			(layer "F.SilkS")
		)
		(fp_rect
			(start -2.450084 2.999994)
			(end 2.450084 -2.999994)
			(stroke
				(width 0)
				(type default)
			)
			(fill no)
			(layer "F.CrtYd")
		)
		(fp_poly
			(pts
				(xy -2.8194 3.6322) (xy -2.8194 -3.6322) (xy 2.8194 -3.6322) (xy 2.8194 1.18364) (xy 2.450084 1.18364)
				(xy 2.450084 -2.999994) (xy -2.450084 -2.999994) (xy -2.450084 2.999994) (xy 2.450084 2.999994)
				(xy 2.450084 1.18618) (xy 2.8194 1.18618) (xy 2.8194 3.6322)
			)
			(stroke
				(width 0)
				(type default)
			)
			(fill no)
			(layer "F.CrtYd")
		)
		(fp_rect
			(start -2.8194 3.6322)
			(end 2.8194 -3.6322)
			(stroke
				(width 0)
				(type default)
			)
			(fill no)
			(layer "F.Fab")
		)
		(pad "1" smd rect
			(at -1.905 2.54)
			(size 0.635 1.651)
			(layers "F.Cu" "F.Mask" "F.Paste")
			(net "P12V_IN")
		)
		(pad "2" smd rect
			(at -0.635 2.54)
			(size 0.635 1.651)
			(layers "F.Cu" "F.Mask" "F.Paste")
			(net "P12V_IN")
		)
		(pad "3" smd rect
			(at 0.635 2.54)
			(size 0.635 1.651)
			(layers "F.Cu" "F.Mask" "F.Paste")
			(net "P12V_IN")
		)
		(pad "4" smd rect
			(at 1.905 2.54)
			(size 0.635 1.651)
			(layers "F.Cu" "F.Mask" "F.Paste")
			(net "GATE_FAN2_R")
		)
		(pad "5" smd rect
			(at 1.905 -2.54)
			(size 0.635 1.651)
			(layers "F.Cu" "F.Mask" "F.Paste")
			(net "P12V_FAN2")
		)
		(pad "6" smd rect
			(at 0.635 -2.54)
			(size 0.635 1.651)
			(layers "F.Cu" "F.Mask" "F.Paste")
			(net "P12V_FAN2")
		)
		(pad "7" smd rect
			(at -0.635 -2.54)
			(size 0.635 1.651)
			(layers "F.Cu" "F.Mask" "F.Paste")
			(net "P12V_FAN2")
		)
		(pad "8" smd rect
			(at -1.905 -2.54)
			(size 0.635 1.651)
			(layers "F.Cu" "F.Mask" "F.Paste")
			(net "P12V_FAN2")
		)
	)
	(footprint ""
		(layer "F.Cu")
		(at 258.064 -232.283 180)
		(property "Reference" "Q21"
			(at 0 0 180)
			(layer "F.SilkS")
			(hide yes)
			(effects
				(font
					(size 1.27 1.27)
				)
			)
		)
		(property "Value" "2N7002K-1-GP"
			(at 0.127 -8.9662 180)
			(unlocked yes)
			(layer "F.Fab")
			(hide yes)
			(effects
				(font
					(size 1.016 1.016)
					(thickness 0.1524)
				)
			)
		)
		(property "Device Type" "SOT23DGS2D4H44"
			(at 0.127 -10.4902 180)
			(unlocked yes)
			(layer "F.Fab")
			(hide yes)
			(effects
				(font
					(size 1.016 1.016)
					(thickness 0.1524)
				)
			)
		)
		(duplicate_pad_numbers_are_jumpers no)
		(fp_line
			(start 1.651 1.778)
			(end 1.651 -1.778)
			(stroke
				(width 0.1524)
				(type default)
			)
			(layer "F.SilkS")
		)
		(fp_line
			(start 1.651 -1.778)
			(end -1.651 -1.778)
			(stroke
				(width 0.1524)
				(type default)
			)
			(layer "F.SilkS")
		)
		(fp_line
			(start -1.651 1.778)
			(end 1.651 1.778)
			(stroke
				(width 0.1524)
				(type default)
			)
			(layer "F.SilkS")
		)
		(fp_line
			(start -1.651 -1.778)
			(end -1.651 1.778)
			(stroke
				(width 0.1524)
				(type default)
			)
			(layer "F.SilkS")
		)
		(fp_poly
			(pts
				(xy -1.778 1.8796) (xy -1.778 -1.8796) (xy 1.778 -1.8796) (xy 1.778 1.8796)
			)
			(stroke
				(width 0)
				(type default)
			)
			(fill no)
			(layer "F.CrtYd")
		)
		(fp_poly
			(pts
				(xy -1.778 1.8796) (xy -1.778 -1.8796) (xy 1.778 -1.8796) (xy 1.778 1.8796)
			)
			(stroke
				(width 0)
				(type default)
			)
			(fill no)
			(layer "F.Fab")
		)
		(pad "D" smd custom
			(at 0 -0.9525 180)
			(size 0.1905 0.1905)
			(layers "F.Cu" "F.Mask" "F.Paste")
			(net "SCC_FULL_PWR_EN_5V_R")
			(options
				(clearance outline)
				(anchor circle)
			)
			(primitives
				(gr_poly
					(pts
						(arc
							(start -0.1778 0.5715)
							(mid -0.321484 0.511984)
							(end -0.381 0.3683)
						)
						(arc
							(start -0.381 -0.3683)
							(mid -0.321484 -0.511984)
							(end -0.1778 -0.5715)
						)
						(arc
							(start 0.1778 -0.5715)
							(mid 0.321484 -0.511984)
							(end 0.381 -0.3683)
						)
						(arc
							(start 0.381 0.3683)
							(mid 0.321484 0.511984)
							(end 0.1778 0.5715)
						)
					)
					(width 0)
					(fill yes)
				)
			)
		)
		(pad "G" smd custom
			(at -0.98425 0.9525 180)
			(size 0.1905 0.1905)
			(layers "F.Cu" "F.Mask" "F.Paste")
			(net "SCC_B_FULL_PWR_EN_12V")
			(options
				(clearance outline)
				(anchor circle)
			)
			(primitives
				(gr_poly
					(pts
						(arc
							(start -0.1778 0.5715)
							(mid -0.321484 0.511984)
							(end -0.381 0.3683)
						)
						(arc
							(start -0.381 -0.3683)
							(mid -0.321484 -0.511984)
							(end -0.1778 -0.5715)
						)
						(arc
							(start 0.1778 -0.5715)
							(mid 0.321484 -0.511984)
							(end 0.381 -0.3683)
						)
						(arc
							(start 0.381 0.3683)
							(mid 0.321484 0.511984)
							(end 0.1778 0.5715)
						)
					)
					(width 0)
					(fill yes)
				)
			)
		)
		(pad "S" smd custom
			(at 0.98425 0.9525 180)
			(size 0.1905 0.1905)
			(layers "F.Cu" "F.Mask" "F.Paste")
			(net "GND")
			(options
				(clearance outline)
				(anchor circle)
			)
			(primitives
				(gr_poly
					(pts
						(arc
							(start -0.1778 0.5715)
							(mid -0.321484 0.511984)
							(end -0.381 0.3683)
						)
						(arc
							(start -0.381 -0.3683)
							(mid -0.321484 -0.511984)
							(end -0.1778 -0.5715)
						)
						(arc
							(start 0.1778 -0.5715)
							(mid 0.321484 -0.511984)
							(end 0.381 -0.3683)
						)
						(arc
							(start 0.381 0.3683)
							(mid 0.321484 0.511984)
							(end 0.1778 0.5715)
						)
					)
					(width 0)
					(fill yes)
				)
			)
		)
	)
	(footprint ""
		(layer "F.Cu")
		(at 427.863 -128.651 180)
		(property "Reference" "R561"
			(at 0 0 180)
			(layer "F.SilkS")
			(hide yes)
			(effects
				(font
					(size 1.27 1.27)
				)
			)
		)
		(property "Value" "1KR2F-3-GP"
			(at 0.064008 -3.993896 180)
			(unlocked yes)
			(layer "F.Fab")
			(hide yes)
			(effects
				(font
					(size 1.016 1.016)
					(thickness 0.1524)
				)
			)
		)
		(property "Device Type" "R402H16"
			(at 0.064008 -5.517896 180)
			(unlocked yes)
			(layer "F.Fab")
			(hide yes)
			(effects
				(font
					(size 1.016 1.016)
					(thickness 0.1524)
				)
			)
		)
		(duplicate_pad_numbers_are_jumpers no)
		(fp_line
			(start 0.508 -0.9398)
			(end -0.508 -0.9398)
			(stroke
				(width 0.1524)
				(type default)
			)
			(layer "F.SilkS")
		)
		(fp_line
			(start -0.508 -0.9398)
			(end -0.508 0.9398)
			(stroke
				(width 0.1524)
				(type default)
			)
			(layer "F.SilkS")
		)
		(fp_rect
			(start -0.508 0.9398)
			(end 0.508 -0.9398)
			(stroke
				(width 0)
				(type default)
			)
			(fill no)
			(layer "F.CrtYd")
		)
		(fp_rect
			(start -0.508 0.9398)
			(end 0.508 -0.9398)
			(stroke
				(width 0)
				(type default)
			)
			(fill no)
			(layer "F.Fab")
		)
		(pad "1" smd custom
			(at 0 -0.4445 180)
			(size 0.1397 0.1397)
			(layers "F.Cu" "F.Mask" "F.Paste")
			(net "P3V3_STBY_B")
			(options
				(clearance outline)
				(anchor circle)
			)
			(primitives
				(gr_poly
					(pts
						(arc
							(start -0.1778 -0.2794)
							(mid -0.249642 -0.249642)
							(end -0.2794 -0.1778)
						)
						(arc
							(start -0.2794 0.1778)
							(mid -0.249642 0.249642)
							(end -0.1778 0.2794)
						)
						(arc
							(start 0.1778 0.2794)
							(mid 0.249642 0.249642)
							(end 0.2794 0.1778)
						)
						(arc
							(start 0.2794 -0.1778)
							(mid 0.249642 -0.249642)
							(end 0.1778 -0.2794)
						)
					)
					(width 0)
					(fill yes)
				)
			)
		)
		(pad "2" smd custom
			(at 0 0.4445 180)
			(size 0.1397 0.1397)
			(layers "F.Cu" "F.Mask" "F.Paste")
			(net "SW_PWR_R_HDD21")
			(options
				(clearance outline)
				(anchor circle)
			)
			(primitives
				(gr_poly
					(pts
						(arc
							(start -0.1778 -0.2794)
							(mid -0.249642 -0.249642)
							(end -0.2794 -0.1778)
						)
						(arc
							(start -0.2794 0.1778)
							(mid -0.249642 0.249642)
							(end -0.1778 0.2794)
						)
						(arc
							(start 0.1778 0.2794)
							(mid 0.249642 0.249642)
							(end 0.2794 0.1778)
						)
						(arc
							(start 0.2794 -0.1778)
							(mid 0.249642 -0.249642)
							(end 0.1778 -0.2794)
						)
					)
					(width 0)
					(fill yes)
				)
			)
		)
	)
	(footprint ""
		(layer "F.Cu")
		(at 425.863004 -369.697 180)
		(property "Reference" "R953"
			(at 0 0 180)
			(layer "F.SilkS")
			(hide yes)
			(effects
				(font
					(size 1.27 1.27)
				)
			)
		)
		(property "Value" "4K7R2F-GP"
			(at 0.064008 -3.993896 180)
			(unlocked yes)
			(layer "F.Fab")
			(hide yes)
			(effects
				(font
					(size 1.016 1.016)
					(thickness 0.1524)
				)
			)
		)
		(property "Device Type" "R402H16"
			(at 0.064008 -5.517896 180)
			(unlocked yes)
			(layer "F.Fab")
			(hide yes)
			(effects
				(font
					(size 1.016 1.016)
					(thickness 0.1524)
				)
			)
		)
		(duplicate_pad_numbers_are_jumpers no)
		(fp_line
			(start 0.508 -0.9398)
			(end -0.508 -0.9398)
			(stroke
				(width 0.1524)
				(type default)
			)
			(layer "F.SilkS")
		)
		(fp_line
			(start -0.508 -0.9398)
			(end -0.508 0.9398)
			(stroke
				(width 0.1524)
				(type default)
			)
			(layer "F.SilkS")
		)
		(fp_rect
			(start -0.508 0.9398)
			(end 0.508 -0.9398)
			(stroke
				(width 0)
				(type default)
			)
			(fill no)
			(layer "F.CrtYd")
		)
		(fp_rect
			(start -0.508 0.9398)
			(end 0.508 -0.9398)
			(stroke
				(width 0)
				(type default)
			)
			(fill no)
			(layer "F.Fab")
		)
		(pad "1" smd custom
			(at 0 -0.4445 180)
			(size 0.1397 0.1397)
			(layers "F.Cu" "F.Mask" "F.Paste")
			(net "P12V_IN")
			(options
				(clearance outline)
				(anchor circle)
			)
			(primitives
				(gr_poly
					(pts
						(arc
							(start -0.1778 -0.2794)
							(mid -0.249642 -0.249642)
							(end -0.2794 -0.1778)
						)
						(arc
							(start -0.2794 0.1778)
							(mid -0.249642 0.249642)
							(end -0.1778 0.2794)
						)
						(arc
							(start 0.1778 0.2794)
							(mid 0.249642 0.249642)
							(end 0.2794 0.1778)
						)
						(arc
							(start 0.2794 -0.1778)
							(mid 0.249642 -0.249642)
							(end 0.1778 -0.2794)
						)
					)
					(width 0)
					(fill yes)
				)
			)
		)
		(pad "2" smd custom
			(at 0 0.4445 180)
			(size 0.1397 0.1397)
			(layers "F.Cu" "F.Mask" "F.Paste")
			(net "FAN_3_TACH0")
			(options
				(clearance outline)
				(anchor circle)
			)
			(primitives
				(gr_poly
					(pts
						(arc
							(start -0.1778 -0.2794)
							(mid -0.249642 -0.249642)
							(end -0.2794 -0.1778)
						)
						(arc
							(start -0.2794 0.1778)
							(mid -0.249642 0.249642)
							(end -0.1778 0.2794)
						)
						(arc
							(start 0.1778 0.2794)
							(mid 0.249642 0.249642)
							(end 0.2794 0.1778)
						)
						(arc
							(start 0.2794 -0.1778)
							(mid 0.249642 -0.249642)
							(end 0.1778 -0.2794)
						)
					)
					(width 0)
					(fill yes)
				)
			)
		)
	)
	(footprint ""
		(layer "F.Cu")
		(at 364.998 -160.02 180)
		(property "Reference" "C283"
			(at 0 0 180)
			(layer "F.SilkS")
			(hide yes)
			(effects
				(font
					(size 1.27 1.27)
				)
			)
		)
		(property "Value" "SC4D7U25V5KX-1-GP"
			(at -0.0762 -6.1214 180)
			(unlocked yes)
			(layer "F.Fab")
			(hide yes)
			(effects
				(font
					(size 1.016 1.016)
					(thickness 0.1524)
				)
			)
		)
		(property "Device Type" "C805H58"
			(at -0.0762 -8.1534 180)
			(unlocked yes)
			(layer "F.Fab")
			(hide yes)
			(effects
				(font
					(size 1.016 1.016)
					(thickness 0.1524)
				)
			)
		)
		(duplicate_pad_numbers_are_jumpers no)
		(fp_line
			(start 0.635 0)
			(end -0.635 0)
			(stroke
				(width 0.508)
				(type default)
			)
			(layer "F.SilkS")
		)
		(fp_rect
			(start -0.9652 1.778)
			(end 0.9652 -1.778)
			(stroke
				(width 0)
				(type default)
			)
			(fill no)
			(layer "F.CrtYd")
		)
		(fp_poly
			(pts
				(xy -0.9652 -1.778) (xy 0.9652 -1.778) (xy 0.9652 1.778) (xy -0.9652 1.778)
			)
			(stroke
				(width 0)
				(type default)
			)
			(fill no)
			(layer "F.Fab")
		)
		(pad "1" smd rect
			(at 0 -0.9652 180)
			(size 1.397 1.143)
			(layers "F.Cu" "F.Mask" "F.Paste")
			(net "P12V_HDD19")
		)
		(pad "2" smd rect
			(at 0 0.9652 180)
			(size 1.397 1.143)
			(layers "F.Cu" "F.Mask" "F.Paste")
			(net "GND")
		)
	)
)
